(kicad_pcb
	(version 20260206)
	(generator "pcbnew")
	(generator_version "10.0")
	(general
		(thickness 1.6)
		(legacy_teardrops no)
	)
	(paper "A4")
	(title_block
		(title "01162023_DA0F0TEBIF0_F0T_Expander_BD_F_brd_V02_OCP.brd")
		(comment 1 "Grand Teton / footprints 8464-8471 of 9728")
	)
	(layers
		(0 "F.Cu" signal "TOP")
		(4 "In1.Cu" signal "GND")
		(6 "In2.Cu" signal "VCC")
		(8 "In3.Cu" signal "VCC1")
		(10 "In4.Cu" signal "GND1")
		(12 "In5.Cu" signal "IN1")
		(14 "In6.Cu" signal "GND2")
		(16 "In7.Cu" signal "IN2")
		(18 "In8.Cu" signal "GND3")
		(20 "In9.Cu" signal "IN3")
		(22 "In10.Cu" signal "GND4")
		(24 "In11.Cu" signal "IN4")
		(26 "In12.Cu" signal "GND5")
		(28 "In13.Cu" signal "IN5")
		(30 "In14.Cu" signal "GND6")
		(32 "In15.Cu" signal "IN6")
		(34 "In16.Cu" signal "GND7")
		(2 "B.Cu" signal "BOTTOM")
		(9 "F.Adhes" user "F.Adhesive")
		(11 "B.Adhes" user "B.Adhesive")
		(13 "F.Paste" user "Package Geometry/Pastemask Top")
		(15 "B.Paste" user "Package Geometry/Pastemask Bottom")
		(5 "F.SilkS" user "Ref Des/Silkscreen Top")
		(7 "B.SilkS" user "Ref Des/Silkscreen Bottom")
		(1 "F.Mask" user "Board Geometry/Soldermask Top")
		(3 "B.Mask" user "Board Geometry/Soldermask Bottom")
		(17 "Dwgs.User" user "User.Drawings")
		(19 "Cmts.User" user "User.Comments")
		(21 "Eco1.User" user "User.Eco1")
		(23 "Eco2.User" user "User.Eco2")
		(25 "Edge.Cuts" user "Board Geometry/Outline")
		(27 "Margin" user)
		(31 "F.CrtYd" user "Package Geometry/Place Bound Top")
		(29 "B.CrtYd" user "Package Geometry/Place Bound Bottom")
		(35 "F.Fab" user "Ref Des/Assembly Top")
		(33 "B.Fab" user "Ref Des/Assembly Bottom")
	)
	(footprint ""
		(layer "B.Cu")
		(at 184.772046 -113.437924 180)
		(property "Reference" "R163"
			(at 0 0 0)
			(layer "B.SilkS")
			(hide yes)
			(effects
				(font
					(size 1.27 1.27)
				)
				(justify mirror)
			)
		)
		(property "Value" ""
			(at 0 0 0)
			(layer "B.Fab")
			(effects
				(font
					(size 1.27 1.27)
				)
				(justify mirror)
			)
		)
		(duplicate_pad_numbers_are_jumpers no)
		(fp_line
			(start 0.7874 0.4064)
			(end 0.7874 -0.4064)
			(stroke
				(width 0.1524)
				(type default)
			)
			(layer "B.SilkS")
		)
		(fp_line
			(start 0.7874 -0.4064)
			(end -0.7874 -0.4064)
			(stroke
				(width 0.1524)
				(type default)
			)
			(layer "B.SilkS")
		)
		(fp_line
			(start -0.7874 0.4064)
			(end 0.7874 0.4064)
			(stroke
				(width 0.1524)
				(type default)
			)
			(layer "B.SilkS")
		)
		(fp_line
			(start -0.7874 -0.4064)
			(end -0.7874 0.4064)
			(stroke
				(width 0.1524)
				(type default)
			)
			(layer "B.SilkS")
		)
		(fp_line
			(start 0.67945 0.3048)
			(end 0.67945 -0.305054)
			(stroke
				(width 0.1)
				(type default)
			)
			(layer "B.Fab")
		)
		(fp_line
			(start 0.67945 -0.305054)
			(end 0.12065 -0.305054)
			(stroke
				(width 0.1)
				(type default)
			)
			(layer "B.Fab")
		)
		(fp_line
			(start 0.12065 0.3048)
			(end 0.67945 0.3048)
			(stroke
				(width 0.1)
				(type default)
			)
			(layer "B.Fab")
		)
		(fp_line
			(start 0.12065 0.2794)
			(end 0.12065 0.3048)
			(stroke
				(width 0.1)
				(type default)
			)
			(layer "B.Fab")
		)
		(fp_line
			(start 0.12065 -0.2794)
			(end -0.12065 -0.2794)
			(stroke
				(width 0.1)
				(type default)
			)
			(layer "B.Fab")
		)
		(fp_line
			(start 0.12065 -0.305054)
			(end 0.12065 -0.2794)
			(stroke
				(width 0.1)
				(type default)
			)
			(layer "B.Fab")
		)
		(fp_line
			(start -0.120396 0.3048)
			(end -0.120396 0.2794)
			(stroke
				(width 0.1)
				(type default)
			)
			(layer "B.Fab")
		)
		(fp_line
			(start -0.120396 0.2794)
			(end 0.12065 0.2794)
			(stroke
				(width 0.1)
				(type default)
			)
			(layer "B.Fab")
		)
		(fp_line
			(start -0.12065 -0.2794)
			(end -0.12065 -0.3048)
			(stroke
				(width 0.1)
				(type default)
			)
			(layer "B.Fab")
		)
		(fp_line
			(start -0.12065 -0.3048)
			(end -0.67945 -0.3048)
			(stroke
				(width 0.1)
				(type default)
			)
			(layer "B.Fab")
		)
		(fp_line
			(start -0.67945 0.3048)
			(end -0.120396 0.3048)
			(stroke
				(width 0.1)
				(type default)
			)
			(layer "B.Fab")
		)
		(fp_line
			(start -0.67945 -0.3048)
			(end -0.67945 0.3048)
			(stroke
				(width 0.1)
				(type default)
			)
			(layer "B.Fab")
		)
		(pad "1" smd circle
			(at 0.40005 0)
			(size 0 0)
			(layers "B.Cu" "B.Mask" "B.Paste")
			(net "SMB_NIC3_R_SDA")
		)
		(pad "2" smd circle
			(at -0.40005 0)
			(size 0 0)
			(layers "B.Cu" "B.Mask" "B.Paste")
			(net "P3V3_NIC3")
		)
	)
	(footprint ""
		(layer "B.Cu")
		(at 45.864272 -145.284952 180)
		(property "Reference" "C850"
			(at 0 0 0)
			(layer "B.SilkS")
			(hide yes)
			(effects
				(font
					(size 1.27 1.27)
				)
				(justify mirror)
			)
		)
		(property "Value" ""
			(at 0 0 0)
			(layer "B.Fab")
			(effects
				(font
					(size 1.27 1.27)
				)
				(justify mirror)
			)
		)
		(duplicate_pad_numbers_are_jumpers no)
		(fp_line
			(start 0.299974 0.150114)
			(end 0.299974 -0.150114)
			(stroke
				(width 0.1)
				(type default)
			)
			(layer "B.Fab")
		)
		(fp_line
			(start 0.299974 -0.150114)
			(end -0.299974 -0.150114)
			(stroke
				(width 0.1)
				(type default)
			)
			(layer "B.Fab")
		)
		(fp_line
			(start -0.299974 0.150114)
			(end 0.299974 0.150114)
			(stroke
				(width 0.1)
				(type default)
			)
			(layer "B.Fab")
		)
		(fp_line
			(start -0.299974 -0.150114)
			(end -0.299974 0.150114)
			(stroke
				(width 0.1)
				(type default)
			)
			(layer "B.Fab")
		)
		(pad "1" smd rect
			(at 0.2667 0)
			(size 0.3048 0.381)
			(layers "B.Cu" "B.Mask" "B.Paste")
			(net "P12V_NIC0")
		)
		(pad "2" smd rect
			(at -0.2667 0)
			(size 0.3048 0.381)
			(layers "B.Cu" "B.Mask" "B.Paste")
			(net "GND")
		)
	)
	(footprint ""
		(layer "B.Cu")
		(at 100.573586 -344.563954 -90)
		(property "Reference" "R6373"
			(at 0 0 90)
			(layer "B.SilkS")
			(hide yes)
			(effects
				(font
					(size 1.27 1.27)
				)
				(justify mirror)
			)
		)
		(property "Value" ""
			(at 0 0 90)
			(layer "B.Fab")
			(effects
				(font
					(size 1.27 1.27)
				)
				(justify mirror)
			)
		)
		(duplicate_pad_numbers_are_jumpers no)
		(fp_line
			(start -0.7874 0.4064)
			(end 0.7874 0.4064)
			(stroke
				(width 0.1524)
				(type default)
			)
			(layer "B.SilkS")
		)
		(fp_line
			(start 0.7874 0.4064)
			(end 0.7874 -0.4064)
			(stroke
				(width 0.1524)
				(type default)
			)
			(layer "B.SilkS")
		)
		(fp_line
			(start -0.7874 -0.4064)
			(end -0.7874 0.4064)
			(stroke
				(width 0.1524)
				(type default)
			)
			(layer "B.SilkS")
		)
		(fp_line
			(start 0.7874 -0.4064)
			(end -0.7874 -0.4064)
			(stroke
				(width 0.1524)
				(type default)
			)
			(layer "B.SilkS")
		)
		(fp_line
			(start -0.67945 0.3048)
			(end -0.120396 0.3048)
			(stroke
				(width 0.1)
				(type default)
			)
			(layer "B.Fab")
		)
		(fp_line
			(start -0.120396 0.3048)
			(end -0.120396 0.2794)
			(stroke
				(width 0.1)
				(type default)
			)
			(layer "B.Fab")
		)
		(fp_line
			(start 0.12065 0.3048)
			(end 0.67945 0.3048)
			(stroke
				(width 0.1)
				(type default)
			)
			(layer "B.Fab")
		)
		(fp_line
			(start 0.67945 0.3048)
			(end 0.67945 -0.305054)
			(stroke
				(width 0.1)
				(type default)
			)
			(layer "B.Fab")
		)
		(fp_line
			(start -0.120396 0.2794)
			(end 0.12065 0.2794)
			(stroke
				(width 0.1)
				(type default)
			)
			(layer "B.Fab")
		)
		(fp_line
			(start 0.12065 0.2794)
			(end 0.12065 0.3048)
			(stroke
				(width 0.1)
				(type default)
			)
			(layer "B.Fab")
		)
		(fp_line
			(start -0.12065 -0.2794)
			(end -0.12065 -0.3048)
			(stroke
				(width 0.1)
				(type default)
			)
			(layer "B.Fab")
		)
		(fp_line
			(start 0.12065 -0.2794)
			(end -0.12065 -0.2794)
			(stroke
				(width 0.1)
				(type default)
			)
			(layer "B.Fab")
		)
		(fp_line
			(start -0.67945 -0.3048)
			(end -0.67945 0.3048)
			(stroke
				(width 0.1)
				(type default)
			)
			(layer "B.Fab")
		)
		(fp_line
			(start -0.12065 -0.3048)
			(end -0.67945 -0.3048)
			(stroke
				(width 0.1)
				(type default)
			)
			(layer "B.Fab")
		)
		(fp_line
			(start 0.12065 -0.305054)
			(end 0.12065 -0.2794)
			(stroke
				(width 0.1)
				(type default)
			)
			(layer "B.Fab")
		)
		(fp_line
			(start 0.67945 -0.305054)
			(end 0.12065 -0.305054)
			(stroke
				(width 0.1)
				(type default)
			)
			(layer "B.Fab")
		)
		(pad "1" smd circle
			(at 0.40005 0 90)
			(size 0 0)
			(layers "B.Cu" "B.Mask" "B.Paste")
			(net "GND")
		)
		(pad "2" smd circle
			(at -0.40005 0 90)
			(size 0 0)
			(layers "B.Cu" "B.Mask" "B.Paste")
			(net "SMB_9ZXL0451E_S3_ADDR0")
		)
	)
	(footprint ""
		(layer "B.Cu")
		(at 126.078488 -282.040584 90)
		(property "Reference" "PR109"
			(at 0 0 90)
			(layer "B.SilkS")
			(hide yes)
			(effects
				(font
					(size 1.27 1.27)
				)
				(justify mirror)
			)
		)
		(property "Value" ""
			(at 0 0 90)
			(layer "B.Fab")
			(effects
				(font
					(size 1.27 1.27)
				)
				(justify mirror)
			)
		)
		(duplicate_pad_numbers_are_jumpers no)
		(fp_line
			(start 0.7874 -0.4064)
			(end -0.7874 -0.4064)
			(stroke
				(width 0.1524)
				(type default)
			)
			(layer "B.SilkS")
		)
		(fp_line
			(start -0.7874 -0.4064)
			(end -0.7874 0.4064)
			(stroke
				(width 0.1524)
				(type default)
			)
			(layer "B.SilkS")
		)
		(fp_line
			(start 0.7874 0.4064)
			(end 0.7874 -0.4064)
			(stroke
				(width 0.1524)
				(type default)
			)
			(layer "B.SilkS")
		)
		(fp_line
			(start -0.7874 0.4064)
			(end 0.7874 0.4064)
			(stroke
				(width 0.1524)
				(type default)
			)
			(layer "B.SilkS")
		)
		(fp_line
			(start 0.67945 -0.305054)
			(end 0.12065 -0.305054)
			(stroke
				(width 0.1)
				(type default)
			)
			(layer "B.Fab")
		)
		(fp_line
			(start 0.12065 -0.305054)
			(end 0.12065 -0.2794)
			(stroke
				(width 0.1)
				(type default)
			)
			(layer "B.Fab")
		)
		(fp_line
			(start -0.12065 -0.3048)
			(end -0.67945 -0.3048)
			(stroke
				(width 0.1)
				(type default)
			)
			(layer "B.Fab")
		)
		(fp_line
			(start -0.67945 -0.3048)
			(end -0.67945 0.3048)
			(stroke
				(width 0.1)
				(type default)
			)
			(layer "B.Fab")
		)
		(fp_line
			(start 0.12065 -0.2794)
			(end -0.12065 -0.2794)
			(stroke
				(width 0.1)
				(type default)
			)
			(layer "B.Fab")
		)
		(fp_line
			(start -0.12065 -0.2794)
			(end -0.12065 -0.3048)
			(stroke
				(width 0.1)
				(type default)
			)
			(layer "B.Fab")
		)
		(fp_line
			(start 0.12065 0.2794)
			(end 0.12065 0.3048)
			(stroke
				(width 0.1)
				(type default)
			)
			(layer "B.Fab")
		)
		(fp_line
			(start -0.120396 0.2794)
			(end 0.12065 0.2794)
			(stroke
				(width 0.1)
				(type default)
			)
			(layer "B.Fab")
		)
		(fp_line
			(start 0.67945 0.3048)
			(end 0.67945 -0.305054)
			(stroke
				(width 0.1)
				(type default)
			)
			(layer "B.Fab")
		)
		(fp_line
			(start 0.12065 0.3048)
			(end 0.67945 0.3048)
			(stroke
				(width 0.1)
				(type default)
			)
			(layer "B.Fab")
		)
		(fp_line
			(start -0.120396 0.3048)
			(end -0.120396 0.2794)
			(stroke
				(width 0.1)
				(type default)
			)
			(layer "B.Fab")
		)
		(fp_line
			(start -0.67945 0.3048)
			(end -0.120396 0.3048)
			(stroke
				(width 0.1)
				(type default)
			)
			(layer "B.Fab")
		)
		(pad "1" smd circle
			(at 0.40005 0 270)
			(size 0 0)
			(layers "B.Cu" "B.Mask" "B.Paste")
			(net "SW_P0V8_PEX1_VOS1")
		)
		(pad "2" smd circle
			(at -0.40005 0 270)
			(size 0 0)
			(layers "B.Cu" "B.Mask" "B.Paste")
			(net "P0V8_PEX1")
		)
	)
	(footprint ""
		(layer "B.Cu")
		(at 403.199854 -301.599854 -90)
		(property "Reference" "C1974"
			(at 0 0 90)
			(layer "B.SilkS")
			(hide yes)
			(effects
				(font
					(size 1.27 1.27)
				)
				(justify mirror)
			)
		)
		(property "Value" ""
			(at 0 0 90)
			(layer "B.Fab")
			(effects
				(font
					(size 1.27 1.27)
				)
				(justify mirror)
			)
		)
		(duplicate_pad_numbers_are_jumpers no)
		(fp_line
			(start -0.299974 0.150114)
			(end 0.299974 0.150114)
			(stroke
				(width 0.1)
				(type default)
			)
			(layer "B.Fab")
		)
		(fp_line
			(start 0.299974 0.150114)
			(end 0.299974 -0.150114)
			(stroke
				(width 0.1)
				(type default)
			)
			(layer "B.Fab")
		)
		(fp_line
			(start -0.299974 -0.150114)
			(end -0.299974 0.150114)
			(stroke
				(width 0.1)
				(type default)
			)
			(layer "B.Fab")
		)
		(fp_line
			(start 0.299974 -0.150114)
			(end -0.299974 -0.150114)
			(stroke
				(width 0.1)
				(type default)
			)
			(layer "B.Fab")
		)
		(pad "1" smd rect
			(at 0.2667 0 90)
			(size 0.3048 0.381)
			(layers "B.Cu" "B.Mask" "B.Paste")
			(net "P0V8_SERDES_VDDA_PEX3")
		)
		(pad "2" smd rect
			(at -0.2667 0 90)
			(size 0.3048 0.381)
			(layers "B.Cu" "B.Mask" "B.Paste")
			(net "GND")
		)
	)
	(footprint ""
		(layer "B.Cu")
		(at 177.649886 -292.099746 90)
		(property "Reference" "C1464"
			(at 0 0 90)
			(layer "B.SilkS")
			(hide yes)
			(effects
				(font
					(size 1.27 1.27)
				)
				(justify mirror)
			)
		)
		(property "Value" ""
			(at 0 0 90)
			(layer "B.Fab")
			(effects
				(font
					(size 1.27 1.27)
				)
				(justify mirror)
			)
		)
		(duplicate_pad_numbers_are_jumpers no)
		(fp_line
			(start 0.299974 -0.150114)
			(end -0.299974 -0.150114)
			(stroke
				(width 0.1)
				(type default)
			)
			(layer "B.Fab")
		)
		(fp_line
			(start -0.299974 -0.150114)
			(end -0.299974 0.150114)
			(stroke
				(width 0.1)
				(type default)
			)
			(layer "B.Fab")
		)
		(fp_line
			(start 0.299974 0.150114)
			(end 0.299974 -0.150114)
			(stroke
				(width 0.1)
				(type default)
			)
			(layer "B.Fab")
		)
		(fp_line
			(start -0.299974 0.150114)
			(end 0.299974 0.150114)
			(stroke
				(width 0.1)
				(type default)
			)
			(layer "B.Fab")
		)
		(pad "1" smd rect
			(at 0.2667 0 270)
			(size 0.3048 0.381)
			(layers "B.Cu" "B.Mask" "B.Paste")
			(net "P0V8_SERDES_VDDA_PEX1")
		)
		(pad "2" smd rect
			(at -0.2667 0 270)
			(size 0.3048 0.381)
			(layers "B.Cu" "B.Mask" "B.Paste")
			(net "GND")
		)
	)
	(footprint ""
		(layer "B.Cu")
		(at 360.24312 -324.163944 -90)
		(property "Reference" "C4382"
			(at 0 0 90)
			(layer "B.SilkS")
			(hide yes)
			(effects
				(font
					(size 1.27 1.27)
				)
				(justify mirror)
			)
		)
		(property "Value" ""
			(at 0 0 90)
			(layer "B.Fab")
			(effects
				(font
					(size 1.27 1.27)
				)
				(justify mirror)
			)
		)
		(duplicate_pad_numbers_are_jumpers no)
		(fp_line
			(start -1.2954 0.5842)
			(end 1.2954 0.5842)
			(stroke
				(width 0.1524)
				(type default)
			)
			(layer "B.SilkS")
		)
		(fp_line
			(start 1.2954 0.5842)
			(end 1.2954 -0.5842)
			(stroke
				(width 0.1524)
				(type default)
			)
			(layer "B.SilkS")
		)
		(fp_line
			(start -1.2954 -0.5842)
			(end -1.2954 0.5842)
			(stroke
				(width 0.1524)
				(type default)
			)
			(layer "B.SilkS")
		)
		(fp_line
			(start 1.2954 -0.5842)
			(end -1.2954 -0.5842)
			(stroke
				(width 0.1524)
				(type default)
			)
			(layer "B.SilkS")
		)
		(fp_line
			(start -0.8636 0.4572)
			(end 0.8636 0.4572)
			(stroke
				(width 0.1)
				(type default)
			)
			(layer "B.Fab")
		)
		(fp_line
			(start 0.8636 0.4572)
			(end 0.8636 0.4064)
			(stroke
				(width 0.1)
				(type default)
			)
			(layer "B.Fab")
		)
		(fp_line
			(start -1.1938 0.4064)
			(end -0.8636 0.4064)
			(stroke
				(width 0.1)
				(type default)
			)
			(layer "B.Fab")
		)
		(fp_line
			(start -0.8636 0.4064)
			(end -0.8636 0.4572)
			(stroke
				(width 0.1)
				(type default)
			)
			(layer "B.Fab")
		)
		(fp_line
			(start 0.8636 0.4064)
			(end 1.1938 0.4064)
			(stroke
				(width 0.1)
				(type default)
			)
			(layer "B.Fab")
		)
		(fp_line
			(start 1.1938 0.4064)
			(end 1.1938 -0.4064)
			(stroke
				(width 0.1)
				(type default)
			)
			(layer "B.Fab")
		)
		(fp_line
			(start -1.1938 -0.4064)
			(end -1.1938 0.4064)
			(stroke
				(width 0.1)
				(type default)
			)
			(layer "B.Fab")
		)
		(fp_line
			(start -0.8636 -0.4064)
			(end -1.1938 -0.4064)
			(stroke
				(width 0.1)
				(type default)
			)
			(layer "B.Fab")
		)
		(fp_line
			(start 0.8636 -0.4064)
			(end 0.8636 -0.4572)
			(stroke
				(width 0.1)
				(type default)
			)
			(layer "B.Fab")
		)
		(fp_line
			(start 1.1938 -0.4064)
			(end 0.8636 -0.4064)
			(stroke
				(width 0.1)
				(type default)
			)
			(layer "B.Fab")
		)
		(fp_line
			(start -0.8636 -0.4572)
			(end -0.8636 -0.4064)
			(stroke
				(width 0.1)
				(type default)
			)
			(layer "B.Fab")
		)
		(fp_line
			(start 0.8636 -0.4572)
			(end -0.8636 -0.4572)
			(stroke
				(width 0.1)
				(type default)
			)
			(layer "B.Fab")
		)
		(pad "1" smd rect
			(at 0.7366 0 180)
			(size 0.7112 0.8128)
			(layers "B.Cu" "B.Mask" "B.Paste")
			(net "P0V8_SERDES_VDDA_PEX3_C8")
		)
		(pad "2" smd rect
			(at -0.7366 0 180)
			(size 0.7112 0.8128)
			(layers "B.Cu" "B.Mask" "B.Paste")
			(net "GND")
		)
	)
	(footprint ""
		(layer "B.Cu")
		(at 181.44998 -288.299906 90)
		(property "Reference" "C3108"
			(at 0 0 90)
			(layer "B.SilkS")
			(hide yes)
			(effects
				(font
					(size 1.27 1.27)
				)
				(justify mirror)
			)
		)
		(property "Value" ""
			(at 0 0 90)
			(layer "B.Fab")
			(effects
				(font
					(size 1.27 1.27)
				)
				(justify mirror)
			)
		)
		(duplicate_pad_numbers_are_jumpers no)
		(fp_line
			(start 0.299974 -0.150114)
			(end -0.299974 -0.150114)
			(stroke
				(width 0.1)
				(type default)
			)
			(layer "B.Fab")
		)
		(fp_line
			(start -0.299974 -0.150114)
			(end -0.299974 0.150114)
			(stroke
				(width 0.1)
				(type default)
			)
			(layer "B.Fab")
		)
		(fp_line
			(start 0.299974 0.150114)
			(end 0.299974 -0.150114)
			(stroke
				(width 0.1)
				(type default)
			)
			(layer "B.Fab")
		)
		(fp_line
			(start -0.299974 0.150114)
			(end 0.299974 0.150114)
			(stroke
				(width 0.1)
				(type default)
			)
			(layer "B.Fab")
		)
		(pad "1" smd rect
			(at 0.2667 0 270)
			(size 0.3048 0.381)
			(layers "B.Cu" "B.Mask" "B.Paste")
			(net "P1V25_PEX1")
		)
		(pad "2" smd rect
			(at -0.2667 0 270)
			(size 0.3048 0.381)
			(layers "B.Cu" "B.Mask" "B.Paste")
			(net "GND")
		)
	)
)
